(kicad_pcb
	(version 20260206)
	(generator "pcbnew")
	(generator_version "10.0")
	(general
		(thickness 1.6)
		(legacy_teardrops no)
	)
	(paper "A4")
	(title_block
		(title "panther-plus-userver — 13130-1b_20150205.brd")
		(comment 1 "Honey Badger (Wiwynn) / footprint 282 of 1509 (U13), pads 238-356 of 1283")
	)
	(layers
		(0 "F.Cu" signal "TOP")
		(4 "In1.Cu" signal "L2")
		(6 "In2.Cu" signal "L3")
		(8 "In3.Cu" signal "L4")
		(10 "In4.Cu" signal "L5")
		(12 "In5.Cu" signal "L6")
		(14 "In6.Cu" signal "L7")
		(16 "In7.Cu" signal "L8")
		(18 "In8.Cu" signal "L9")
		(20 "In9.Cu" signal "L10")
		(22 "In10.Cu" signal "L11")
		(2 "B.Cu" signal "BOTTOM")
		(9 "F.Adhes" user "F.Adhesive")
		(11 "B.Adhes" user "B.Adhesive")
		(13 "F.Paste" user "Package Geometry/Pastemask Top")
		(15 "B.Paste" user "Package Geometry/Pastemask Bottom")
		(5 "F.SilkS" user "Ref Des/Silkscreen Top")
		(7 "B.SilkS" user "Ref Des/Silkscreen Bottom")
		(1 "F.Mask" user "Board Geometry/Soldermask Top")
		(3 "B.Mask" user "Board Geometry/Soldermask Bottom")
		(17 "Dwgs.User" user "User.Drawings")
		(19 "Cmts.User" user "User.Comments")
		(21 "Eco1.User" user "User.Eco1")
		(23 "Eco2.User" user "User.Eco2")
		(25 "Edge.Cuts" user "Board Geometry/Outline")
		(27 "Margin" user)
		(31 "F.CrtYd" user "Package Geometry/Place Bound Top")
		(29 "B.CrtYd" user "Package Geometry/Place Bound Bottom")
		(35 "F.Fab" user "Ref Des/Assembly Top")
		(33 "B.Fab" user "Ref Des/Assembly Bottom")
	)
	(footprint ""
		(layer "F.Cu")
		(at 95.849948 -39.200074 180)
		(property "Reference" "U13"
			(at 0 0 180)
			(layer "F.SilkS")
			(hide yes)
			(effects
				(font
					(size 1.27 1.27)
				)
			)
		)
		(property "Value" "AVOTON-GP"
			(at -25.0317 -2.4892 180)
			(unlocked yes)
			(layer "F.Fab")
			(hide yes)
			(effects
				(font
					(size 1.016 1.016)
					(thickness 0.1524)
				)
			)
		)
		(property "Device Type" "BGA1283M3428-3H197"
			(at -25.0317 -4.0132 180)
			(unlocked yes)
			(layer "F.Fab")
			(hide yes)
			(effects
				(font
					(size 1.016 1.016)
					(thickness 0.1524)
				)
			)
		)
		(duplicate_pad_numbers_are_jumpers no)
		(pad "AJ47" smd circle
			(at 6.84276 0.81534 180)
			(size 0.3048 0.3048)
			(layers "F.Cu" "F.Mask" "F.Paste")
			(net "GND")
		)
		(pad "AJ63" smd circle
			(at 14.7955 0.56388 180)
			(size 0.3048 0.3048)
			(layers "F.Cu" "F.Mask" "F.Paste")
			(net "RTC_X2PAD")
		)
		(pad "AJ65" smd circle
			(at 15.75308 0.61722 180)
			(size 0.3048 0.3048)
			(layers "F.Cu" "F.Mask" "F.Paste")
			(net "RTC_X1PAD")
		)
		(pad "AK3" smd circle
			(at -15.24762 1.28524 180)
			(size 0.3048 0.3048)
			(layers "F.Cu" "F.Mask" "F.Paste")
			(net "GND")
		)
		(pad "AK5" smd circle
			(at -14.01318 1.31572 180)
			(size 0.3048 0.3048)
			(layers "F.Cu" "F.Mask" "F.Paste")
			(net "GND")
		)
		(pad "AK20" smd circle
			(at -6.84276 1.05664 180)
			(size 0.3048 0.3048)
			(layers "F.Cu" "F.Mask" "F.Paste")
			(net "PVCCP")
		)
		(pad "AK62" smd circle
			(at 14.08176 1.11506 180)
			(size 0.3048 0.3048)
			(layers "F.Cu" "F.Mask" "F.Paste")
			(net "GND")
		)
		(pad "AK64" smd circle
			(at 15.24254 1.1049 180)
			(size 0.3048 0.3048)
			(layers "F.Cu" "F.Mask" "F.Paste")
			(net "GND")
		)
		(pad "AK66" smd oval
			(at 16.24838 1.33604 180)
			(size 0.3429 0.254)
			(layers "F.Cu" "F.Mask" "F.Paste")
			(net "GND")
		)
		(pad "AL1" smd oval
			(at -16.24838 1.54178 180)
			(size 0.3429 0.254)
			(layers "F.Cu" "F.Mask" "F.Paste")
			(net "GND")
		)
		(pad "AL2" smd circle
			(at -15.64132 1.8923 180)
			(size 0.3048 0.3048)
			(layers "F.Cu" "F.Mask" "F.Paste")
			(net "M_A_DQ28")
		)
		(pad "AL4" smd circle
			(at -14.89964 1.89738 180)
			(size 0.3048 0.3048)
			(layers "F.Cu" "F.Mask" "F.Paste")
			(net "M_A_DQ29")
		)
		(pad "AL5" smd circle
			(at -14.20368 1.9939 180)
			(size 0.3048 0.3048)
			(layers "F.Cu" "F.Mask" "F.Paste")
			(net "GND")
		)
		(pad "AL8" smd circle
			(at -12.96416 1.75514 180)
			(size 0.3048 0.3048)
			(layers "F.Cu" "F.Mask" "F.Paste")
			(net "M_A_DQ2")
		)
		(pad "AL9" smd circle
			(at -12.20216 1.75514 180)
			(size 0.3048 0.3048)
			(layers "F.Cu" "F.Mask" "F.Paste")
			(net "GND")
		)
		(pad "AL11" smd circle
			(at -11.44016 1.75514 180)
			(size 0.3048 0.3048)
			(layers "F.Cu" "F.Mask" "F.Paste")
			(net "M_A_DQS_DP0")
		)
		(pad "AL12" smd circle
			(at -10.67816 1.75514 180)
			(size 0.3048 0.3048)
			(layers "F.Cu" "F.Mask" "F.Paste")
			(net "M_A_DQS_DN0")
		)
		(pad "AL14" smd circle
			(at -9.91616 1.75514 180)
			(size 0.3048 0.3048)
			(layers "F.Cu" "F.Mask" "F.Paste")
			(net "GND")
		)
		(pad "AL15" smd circle
			(at -9.15416 1.75514 180)
			(size 0.3048 0.3048)
			(layers "F.Cu" "F.Mask" "F.Paste")
			(net "M_A_DQ5")
		)
		(pad "AL17" smd circle
			(at -8.39216 1.75514 180)
			(size 0.3048 0.3048)
			(layers "F.Cu" "F.Mask" "F.Paste")
			(net "GND")
		)
		(pad "AL18" smd circle
			(at -7.63016 1.75514 180)
			(size 0.3048 0.3048)
			(layers "F.Cu" "F.Mask" "F.Paste")
			(net "GND")
		)
		(pad "AL20" smd circle
			(at -6.92912 1.75514 180)
			(size 0.3048 0.3048)
			(layers "F.Cu" "F.Mask" "F.Paste")
			(net "GND")
		)
		(pad "AL21" smd circle
			(at -5.99948 1.6002 180)
			(size 0.381 0.381)
			(layers "F.Cu" "F.Mask" "F.Paste")
			(net "PVCCP")
		)
		(pad "AL23" smd circle
			(at -5.20192 1.6002 180)
			(size 0.381 0.381)
			(layers "F.Cu" "F.Mask" "F.Paste")
			(net "PVCCP")
		)
		(pad "AL25" smd circle
			(at -4.39928 1.6002 180)
			(size 0.381 0.381)
			(layers "F.Cu" "F.Mask" "F.Paste")
			(net "PVCCP")
		)
		(pad "AL26" smd circle
			(at -3.60172 1.6002 180)
			(size 0.381 0.381)
			(layers "F.Cu" "F.Mask" "F.Paste")
			(net "PVCCP")
		)
		(pad "AL28" smd circle
			(at -2.79908 1.6002 180)
			(size 0.381 0.381)
			(layers "F.Cu" "F.Mask" "F.Paste")
			(net "P1V0")
		)
		(pad "AL29" smd circle
			(at -2.00152 1.6002 180)
			(size 0.381 0.381)
			(layers "F.Cu" "F.Mask" "F.Paste")
			(net "GND")
		)
		(pad "AL31" smd circle
			(at -1.19888 1.6002 180)
			(size 0.381 0.381)
			(layers "F.Cu" "F.Mask" "F.Paste")
			(net "VCCCORE7VIDSI0GT_1P03")
		)
		(pad "AL32" smd circle
			(at -0.40132 1.6002 180)
			(size 0.381 0.381)
			(layers "F.Cu" "F.Mask" "F.Paste")
			(net "VCCCORE6VIDSI0GT_1P03")
		)
		(pad "AL34" smd circle
			(at 0.40132 1.6002 180)
			(size 0.381 0.381)
			(layers "F.Cu" "F.Mask" "F.Paste")
			(net "TP_CPU_RSVD8")
		)
		(pad "AL36" smd circle
			(at 1.19888 1.6002 180)
			(size 0.381 0.381)
			(layers "F.Cu" "F.Mask" "F.Paste")
			(net "PVNN")
		)
		(pad "AL38" smd circle
			(at 2.00152 1.6002 180)
			(size 0.381 0.381)
			(layers "F.Cu" "F.Mask" "F.Paste")
			(net "GND")
		)
		(pad "AL39" smd circle
			(at 2.79908 1.6002 180)
			(size 0.381 0.381)
			(layers "F.Cu" "F.Mask" "F.Paste")
			(net "PVNN")
		)
		(pad "AL41" smd circle
			(at 3.60172 1.6002 180)
			(size 0.381 0.381)
			(layers "F.Cu" "F.Mask" "F.Paste")
			(net "P1V8")
		)
		(pad "AL42" smd circle
			(at 4.39928 1.6002 180)
			(size 0.381 0.381)
			(layers "F.Cu" "F.Mask" "F.Paste")
			(net "GND")
		)
		(pad "AL44" smd circle
			(at 5.20192 1.6002 180)
			(size 0.381 0.381)
			(layers "F.Cu" "F.Mask" "F.Paste")
			(net "GND")
		)
		(pad "AL46" smd circle
			(at 5.99948 1.6002 180)
			(size 0.381 0.381)
			(layers "F.Cu" "F.Mask" "F.Paste")
			(net "MEMORY_CPU_HOT#")
		)
		(pad "AL47" smd circle
			(at 6.92912 1.51638 180)
			(size 0.3048 0.3048)
			(layers "F.Cu" "F.Mask" "F.Paste")
			(net "CTBTRIGOUT")
		)
		(pad "AL49" smd circle
			(at 7.63016 1.51638 180)
			(size 0.3048 0.3048)
			(layers "F.Cu" "F.Mask" "F.Paste")
			(net "BIOS_POST_CMPLT#")
		)
		(pad "AL50" smd circle
			(at 8.39216 1.51638 180)
			(size 0.3048 0.3048)
			(layers "F.Cu" "F.Mask" "F.Paste")
			(net "GND")
		)
		(pad "AL52" smd circle
			(at 9.15416 1.51638 180)
			(size 0.3048 0.3048)
			(layers "F.Cu" "F.Mask" "F.Paste")
			(net "IRQ_MCERR_R#")
		)
		(pad "AL53" smd circle
			(at 9.91616 1.51638 180)
			(size 0.3048 0.3048)
			(layers "F.Cu" "F.Mask" "F.Paste")
			(net "LPC_CPU_LAD2")
		)
		(pad "AL55" smd circle
			(at 10.67816 1.51638 180)
			(size 0.3048 0.3048)
			(layers "F.Cu" "F.Mask" "F.Paste")
			(net "GND")
		)
		(pad "AL56" smd circle
			(at 11.44016 1.51638 180)
			(size 0.3048 0.3048)
			(layers "F.Cu" "F.Mask" "F.Paste")
			(net "IRQ_NMI_R")
		)
		(pad "AL58" smd circle
			(at 12.20216 1.51638 180)
			(size 0.3048 0.3048)
			(layers "F.Cu" "F.Mask" "F.Paste")
			(net "SMBUS_HOST_ALRT#")
		)
		(pad "AL59" smd circle
			(at 12.96416 1.51638 180)
			(size 0.3048 0.3048)
			(layers "F.Cu" "F.Mask" "F.Paste")
			(net "GND")
		)
		(pad "AL62" smd circle
			(at 14.20368 1.80848 180)
			(size 0.3048 0.3048)
			(layers "F.Cu" "F.Mask" "F.Paste")
			(net "CPU_ERR_N1")
		)
		(pad "AL63" smd circle
			(at 14.89964 1.71704 180)
			(size 0.3048 0.3048)
			(layers "F.Cu" "F.Mask" "F.Paste")
			(net "CPU_ERR_N2")
		)
		(pad "AL65" smd circle
			(at 15.63878 1.68402 180)
			(size 0.3048 0.3048)
			(layers "F.Cu" "F.Mask" "F.Paste")
			(net "CPU_ERR_N0")
		)
		(pad "AM8" smd circle
			(at -12.96416 2.45618 180)
			(size 0.3048 0.3048)
			(layers "F.Cu" "F.Mask" "F.Paste")
			(net "M_A_DQ3")
		)
		(pad "AM9" smd circle
			(at -12.20216 2.45618 180)
			(size 0.3048 0.3048)
			(layers "F.Cu" "F.Mask" "F.Paste")
			(net "M_A_DQ7")
		)
		(pad "AM11" smd circle
			(at -11.44016 2.45618 180)
			(size 0.3048 0.3048)
			(layers "F.Cu" "F.Mask" "F.Paste")
			(net "M_A_DQ6")
		)
		(pad "AM12" smd circle
			(at -10.67816 2.45618 180)
			(size 0.3048 0.3048)
			(layers "F.Cu" "F.Mask" "F.Paste")
			(net "GND")
		)
		(pad "AM14" smd circle
			(at -9.91616 2.45618 180)
			(size 0.3048 0.3048)
			(layers "F.Cu" "F.Mask" "F.Paste")
			(net "M_A_DQ1")
		)
		(pad "AM15" smd circle
			(at -9.15416 2.45618 180)
			(size 0.3048 0.3048)
			(layers "F.Cu" "F.Mask" "F.Paste")
			(net "M_A_DQ0")
		)
		(pad "AM17" smd circle
			(at -8.39216 2.45618 180)
			(size 0.3048 0.3048)
			(layers "F.Cu" "F.Mask" "F.Paste")
			(net "M_A_DQ4")
		)
		(pad "AM18" smd circle
			(at -7.63016 2.45618 180)
			(size 0.3048 0.3048)
			(layers "F.Cu" "F.Mask" "F.Paste")
			(net "GND")
		)
		(pad "AM20" smd circle
			(at -6.92912 2.45618 180)
			(size 0.3048 0.3048)
			(layers "F.Cu" "F.Mask" "F.Paste")
			(net "GND")
		)
		(pad "AM21" smd circle
			(at -5.99948 2.4003 180)
			(size 0.381 0.381)
			(layers "F.Cu" "F.Mask" "F.Paste")
			(net "GND")
		)
		(pad "AM23" smd circle
			(at -5.20192 2.4003 180)
			(size 0.381 0.381)
			(layers "F.Cu" "F.Mask" "F.Paste")
			(net "GND")
		)
		(pad "AM25" smd circle
			(at -4.39928 2.4003 180)
			(size 0.381 0.381)
			(layers "F.Cu" "F.Mask" "F.Paste")
			(net "PVNN")
		)
		(pad "AM26" smd circle
			(at -3.60172 2.4003 180)
			(size 0.381 0.381)
			(layers "F.Cu" "F.Mask" "F.Paste")
			(net "PVNN")
		)
		(pad "AM28" smd circle
			(at -2.79908 2.4003 180)
			(size 0.381 0.381)
			(layers "F.Cu" "F.Mask" "F.Paste")
			(net "PVNN")
		)
		(pad "AM29" smd circle
			(at -2.00152 2.4003 180)
			(size 0.381 0.381)
			(layers "F.Cu" "F.Mask" "F.Paste")
			(net "PVNN")
		)
		(pad "AM31" smd circle
			(at -1.19888 2.4003 180)
			(size 0.381 0.381)
			(layers "F.Cu" "F.Mask" "F.Paste")
			(net "PVNN")
		)
		(pad "AM32" smd circle
			(at -0.40132 2.4003 180)
			(size 0.381 0.381)
			(layers "F.Cu" "F.Mask" "F.Paste")
			(net "PVNN")
		)
		(pad "AM34" smd circle
			(at 0.40132 2.4003 180)
			(size 0.381 0.381)
			(layers "F.Cu" "F.Mask" "F.Paste")
			(net "PVNN")
		)
		(pad "AM36" smd circle
			(at 1.19888 2.4003 180)
			(size 0.381 0.381)
			(layers "F.Cu" "F.Mask" "F.Paste")
			(net "PVNN")
		)
		(pad "AM38" smd circle
			(at 2.00152 2.4003 180)
			(size 0.381 0.381)
			(layers "F.Cu" "F.Mask" "F.Paste")
			(net "PVNN")
		)
		(pad "AM39" smd circle
			(at 2.79908 2.4003 180)
			(size 0.381 0.381)
			(layers "F.Cu" "F.Mask" "F.Paste")
			(net "PVNN")
		)
		(pad "AM41" smd circle
			(at 3.60172 2.4003 180)
			(size 0.381 0.381)
			(layers "F.Cu" "F.Mask" "F.Paste")
			(net "PVNN")
		)
		(pad "AM42" smd circle
			(at 4.39928 2.4003 180)
			(size 0.381 0.381)
			(layers "F.Cu" "F.Mask" "F.Paste")
			(net "PVNN")
		)
		(pad "AM44" smd circle
			(at 5.20192 2.4003 180)
			(size 0.381 0.381)
			(layers "F.Cu" "F.Mask" "F.Paste")
			(net "GND")
		)
		(pad "AM46" smd circle
			(at 5.99948 2.4003 180)
			(size 0.381 0.381)
			(layers "F.Cu" "F.Mask" "F.Paste")
			(net "GND")
		)
		(pad "AM47" smd circle
			(at 6.92912 2.21742 180)
			(size 0.3048 0.3048)
			(layers "F.Cu" "F.Mask" "F.Paste")
			(net "CTBTRIGINOUT")
		)
		(pad "AM49" smd circle
			(at 7.63016 2.21742 180)
			(size 0.3048 0.3048)
			(layers "F.Cu" "F.Mask" "F.Paste")
			(net "LPC_CPU_R_CLKOUT1")
		)
		(pad "AM50" smd circle
			(at 8.39216 2.21742 180)
			(size 0.3048 0.3048)
			(layers "F.Cu" "F.Mask" "F.Paste")
			(net "GND")
		)
		(pad "AM52" smd circle
			(at 9.15416 2.21742 180)
			(size 0.3048 0.3048)
			(layers "F.Cu" "F.Mask" "F.Paste")
			(net "IRQ_CPU_IERR#")
		)
		(pad "AM53" smd circle
			(at 9.91616 2.21742 180)
			(size 0.3048 0.3048)
			(layers "F.Cu" "F.Mask" "F.Paste")
			(net "LPC_CPU_LAD1")
		)
		(pad "AM55" smd circle
			(at 10.67816 2.21742 180)
			(size 0.3048 0.3048)
			(layers "F.Cu" "F.Mask" "F.Paste")
			(net "GND")
		)
		(pad "AM56" smd circle
			(at 11.44016 2.21742 180)
			(size 0.3048 0.3048)
			(layers "F.Cu" "F.Mask" "F.Paste")
			(net "CLK_14M_CPU")
		)
		(pad "AM58" smd circle
			(at 12.20216 2.21742 180)
			(size 0.3048 0.3048)
			(layers "F.Cu" "F.Mask" "F.Paste")
			(net "PMU_RESETBUTTON_R#")
		)
		(pad "AM59" smd circle
			(at 12.96416 2.21742 180)
			(size 0.3048 0.3048)
			(layers "F.Cu" "F.Mask" "F.Paste")
			(net "GND")
		)
		(pad "AN2" smd circle
			(at -15.63878 2.8194 180)
			(size 0.3048 0.3048)
			(layers "F.Cu" "F.Mask" "F.Paste")
			(net "M_A_DQ25")
		)
		(pad "AN4" smd circle
			(at -14.89964 2.78638 180)
			(size 0.3048 0.3048)
			(layers "F.Cu" "F.Mask" "F.Paste")
			(net "M_A_DQ24")
		)
		(pad "AN5" smd circle
			(at -14.20368 2.69494 180)
			(size 0.3048 0.3048)
			(layers "F.Cu" "F.Mask" "F.Paste")
			(net "GND")
		)
		(pad "AN47" smd circle
			(at 6.84276 2.91592 180)
			(size 0.3048 0.3048)
			(layers "F.Cu" "F.Mask" "F.Paste")
			(net "GND")
		)
		(pad "AN62" smd circle
			(at 14.20368 2.50698 180)
			(size 0.3048 0.3048)
			(layers "F.Cu" "F.Mask" "F.Paste")
			(net "SMBUS_HOST_CLK")
		)
		(pad "AN63" smd circle
			(at 14.89964 2.60604 180)
			(size 0.3048 0.3048)
			(layers "F.Cu" "F.Mask" "F.Paste")
			(net "SMBUS_SW_R_EN")
		)
		(pad "AN65" smd circle
			(at 15.64132 2.61112 180)
			(size 0.3048 0.3048)
			(layers "F.Cu" "F.Mask" "F.Paste")
			(net "SMBUS_PECI_DATA")
		)
		(pad "AN66" smd oval
			(at 16.24838 2.96164 180)
			(size 0.3429 0.254)
			(layers "F.Cu" "F.Mask" "F.Paste")
			(net "GND")
		)
		(pad "AP1" smd oval
			(at -16.24838 3.16738 180)
			(size 0.3429 0.254)
			(layers "F.Cu" "F.Mask" "F.Paste")
			(net "M_A_DQS_DN3")
		)
		(pad "AP3" smd circle
			(at -15.24254 3.39852 180)
			(size 0.3048 0.3048)
			(layers "F.Cu" "F.Mask" "F.Paste")
			(net "M_A_DQS_DP3")
		)
		(pad "AP5" smd circle
			(at -14.08176 3.38836 180)
			(size 0.3048 0.3048)
			(layers "F.Cu" "F.Mask" "F.Paste")
			(net "GND")
		)
		(pad "AP20" smd circle
			(at -6.84276 3.15722 180)
			(size 0.3048 0.3048)
			(layers "F.Cu" "F.Mask" "F.Paste")
			(net "TP_CPU_RSVD7")
		)
		(pad "AP21" smd circle
			(at -5.99948 3.2004 180)
			(size 0.381 0.381)
			(layers "F.Cu" "F.Mask" "F.Paste")
			(net "TP_CPU_RSVD6")
		)
		(pad "AP23" smd circle
			(at -5.20192 3.2004 180)
			(size 0.381 0.381)
			(layers "F.Cu" "F.Mask" "F.Paste")
			(net "GND")
		)
		(pad "AP25" smd circle
			(at -4.39928 3.2004 180)
			(size 0.381 0.381)
			(layers "F.Cu" "F.Mask" "F.Paste")
			(net "GND")
		)
		(pad "AP26" smd circle
			(at -3.60172 3.2004 180)
			(size 0.381 0.381)
			(layers "F.Cu" "F.Mask" "F.Paste")
			(net "GND")
		)
		(pad "AP28" smd circle
			(at -2.79908 3.2004 180)
			(size 0.381 0.381)
			(layers "F.Cu" "F.Mask" "F.Paste")
			(net "GND")
		)
		(pad "AP29" smd circle
			(at -2.00152 3.2004 180)
			(size 0.381 0.381)
			(layers "F.Cu" "F.Mask" "F.Paste")
			(net "GND")
		)
		(pad "AP31" smd circle
			(at -1.19888 3.2004 180)
			(size 0.381 0.381)
			(layers "F.Cu" "F.Mask" "F.Paste")
			(net "GND")
		)
		(pad "AP32" smd circle
			(at -0.40132 3.2004 180)
			(size 0.381 0.381)
			(layers "F.Cu" "F.Mask" "F.Paste")
			(net "GND")
		)
		(pad "AP34" smd circle
			(at 0.40132 3.2004 180)
			(size 0.381 0.381)
			(layers "F.Cu" "F.Mask" "F.Paste")
			(net "GND")
		)
		(pad "AP36" smd circle
			(at 1.19888 3.2004 180)
			(size 0.381 0.381)
			(layers "F.Cu" "F.Mask" "F.Paste")
			(net "GND")
		)
		(pad "AP38" smd circle
			(at 2.00152 3.2004 180)
			(size 0.381 0.381)
			(layers "F.Cu" "F.Mask" "F.Paste")
			(net "GND")
		)
		(pad "AP39" smd circle
			(at 2.79908 3.2004 180)
			(size 0.381 0.381)
			(layers "F.Cu" "F.Mask" "F.Paste")
			(net "GND")
		)
		(pad "AP41" smd circle
			(at 3.60172 3.2004 180)
			(size 0.381 0.381)
			(layers "F.Cu" "F.Mask" "F.Paste")
			(net "GND")
		)
		(pad "AP42" smd circle
			(at 4.39928 3.2004 180)
			(size 0.381 0.381)
			(layers "F.Cu" "F.Mask" "F.Paste")
			(net "GND")
		)
		(pad "AP44" smd circle
			(at 5.20192 3.2004 180)
			(size 0.381 0.381)
			(layers "F.Cu" "F.Mask" "F.Paste")
			(net "GND")
		)
		(pad "AP46" smd circle
			(at 5.99948 3.2004 180)
			(size 0.381 0.381)
			(layers "F.Cu" "F.Mask" "F.Paste")
			(net "GND")
		)
		(pad "AP62" smd circle
			(at 14.01318 3.18516 180)
			(size 0.3048 0.3048)
			(layers "F.Cu" "F.Mask" "F.Paste")
			(net "SMBUS_HOST_DATA")
		)
		(pad "AP64" smd circle
			(at 15.24762 3.21564 180)
			(size 0.3048 0.3048)
			(layers "F.Cu" "F.Mask" "F.Paste")
			(net "GND")
		)
		(pad "AR2" smd circle
			(at -15.75308 3.8862 180)
			(size 0.3048 0.3048)
			(layers "F.Cu" "F.Mask" "F.Paste")
			(net "M_A_DQ30")
		)
		(pad "AR4" smd circle
			(at -14.7955 3.937 180)
			(size 0.3048 0.3048)
			(layers "F.Cu" "F.Mask" "F.Paste")
			(net "M_A_DQ31")
		)
		(pad "AR7" smd circle
			(at -13.34516 3.74142 180)
			(size 0.3048 0.3048)
			(layers "F.Cu" "F.Mask" "F.Paste")
			(net "M_A_DQS_DN1")
		)
		(pad "AR8" smd circle
			(at -12.58316 3.74142 180)
			(size 0.3048 0.3048)
			(layers "F.Cu" "F.Mask" "F.Paste")
			(net "GND")
		)
		(pad "AR10" smd circle
			(at -11.82116 3.74142 180)
			(size 0.3048 0.3048)
			(layers "F.Cu" "F.Mask" "F.Paste")
			(net "M_A_DQ15")
		)
	)
)
